(kicad_pcb
	(version 20260206)
	(generator "pcbnew")
	(generator_version "10.0")
	(general
		(thickness 1.6)
		(legacy_teardrops no)
	)
	(paper "A4")
	(title_block
		(title "04192023_DAF0TMB3IC0_F0TG_MB_C_brd_V02_OCP.brd")
		(comment 1 "Grand Teton / footprint 3508 of 8354 (J105), pads 1-48 of 48")
	)
	(layers
		(0 "F.Cu" signal "TOP")
		(4 "In1.Cu" signal "GND")
		(6 "In2.Cu" signal "IN1")
		(8 "In3.Cu" signal "GND1")
		(10 "In4.Cu" signal "IN2")
		(12 "In5.Cu" signal "GND2")
		(14 "In6.Cu" signal "IN3")
		(16 "In7.Cu" signal "GND3")
		(18 "In8.Cu" signal "VCC")
		(20 "In9.Cu" signal "VCC1")
		(22 "In10.Cu" signal "GND4")
		(24 "In11.Cu" signal "IN4")
		(26 "In12.Cu" signal "GND5")
		(28 "In13.Cu" signal "IN5")
		(30 "In14.Cu" signal "GND6")
		(32 "In15.Cu" signal "IN6")
		(34 "In16.Cu" signal "GND7")
		(2 "B.Cu" signal "BOTTOM")
		(9 "F.Adhes" user "F.Adhesive")
		(11 "B.Adhes" user "B.Adhesive")
		(13 "F.Paste" user "Package Geometry/Pastemask Top")
		(15 "B.Paste" user "Package Geometry/Pastemask Bottom")
		(5 "F.SilkS" user "Ref Des/Silkscreen Top")
		(7 "B.SilkS" user "Ref Des/Silkscreen Bottom")
		(1 "F.Mask" user "Board Geometry/Soldermask Top")
		(3 "B.Mask" user "Board Geometry/Soldermask Bottom")
		(17 "Dwgs.User" user "User.Drawings")
		(19 "Cmts.User" user "User.Comments")
		(21 "Eco1.User" user "User.Eco1")
		(23 "Eco2.User" user "User.Eco2")
		(25 "Edge.Cuts" user "Board Geometry/Outline")
		(27 "Margin" user)
		(31 "F.CrtYd" user "Package Geometry/Place Bound Top")
		(29 "B.CrtYd" user "Package Geometry/Place Bound Bottom")
		(35 "F.Fab" user "Ref Des/Assembly Top")
		(33 "B.Fab" user "Ref Des/Assembly Bottom")
	)
	(footprint ""
		(layer "F.Cu")
		(at 398.750028 -440.489848)
		(property "Reference" "J105"
			(at 19.875754 19.509486 0)
			(unlocked yes)
			(layer "F.SilkS")
			(effects
				(font
					(size 0.7874 0.5842)
					(thickness 0.1524)
				)
				(justify left)
			)
		)
		(property "Value" ""
			(at 0 0 0)
			(layer "F.Fab")
			(effects
				(font
					(size 1.27 1.27)
				)
			)
		)
		(duplicate_pad_numbers_are_jumpers no)
		(pad "A1" thru_hole rect
			(at 0 0 180)
			(size 0.766318 0.766318)
			(drill 0.359918)
			(layers "*.Cu" "*.Mask")
			(remove_unused_layers no)
			(net "GPU_3V3IO_RSVD4")
			(clearance 0.0508)
			(thermal_gap 0.0508)
			(padstack
				(mode front_inner_back)
				(layer "Inner"
					(shape circle)
					(size 0.766318 0.766318)
					(clearance 0.0508)
				)
				(layer "B.Cu"
					(shape rect)
					(size 0.766318 0.766318)
					(clearance 0.0508)
				)
			)
		)
		(pad "A2" thru_hole circle
			(at 1.999996 0.199898 180)
			(size 0.906272 0.906272)
			(drill 0.499872)
			(layers "*.Cu" "*.Mask")
			(remove_unused_layers no)
			(net "GND")
			(clearance 0.0508)
			(thermal_gap 0.0508)
		)
		(pad "A3" thru_hole circle
			(at 3.999992 0 180)
			(size 0.766318 0.766318)
			(drill 0.359918)
			(layers "*.Cu" "*.Mask")
			(remove_unused_layers no)
			(net "GPU_WP_HW_CTRL_ISO_N")
			(clearance 0.0508)
			(thermal_gap 0.0508)
		)
		(pad "A4" thru_hole circle
			(at 5.999988 0.199898 180)
			(size 0.906272 0.906272)
			(drill 0.499872)
			(layers "*.Cu" "*.Mask")
			(remove_unused_layers no)
			(net "GND")
			(clearance 0.0508)
			(thermal_gap 0.0508)
		)
		(pad "A5" thru_hole circle
			(at 7.999984 0 180)
			(size 0.766318 0.766318)
			(drill 0.359918)
			(layers "*.Cu" "*.Mask")
			(remove_unused_layers no)
			(net "GPU_3V3IO_RSVD3")
			(clearance 0.0508)
			(thermal_gap 0.0508)
		)
		(pad "A6" thru_hole circle
			(at 9.99998 0.199898 180)
			(size 0.906272 0.906272)
			(drill 0.499872)
			(layers "*.Cu" "*.Mask")
			(remove_unused_layers no)
			(net "GND")
			(clearance 0.0508)
			(thermal_gap 0.0508)
		)
		(pad "A7" thru_hole circle
			(at 11.999976 0 180)
			(size 0.766318 0.766318)
			(drill 0.359918)
			(layers "*.Cu" "*.Mask")
			(remove_unused_layers no)
			(net "GPU_3V3IO_RSVD1")
			(clearance 0.0508)
			(thermal_gap 0.0508)
		)
		(pad "A8" thru_hole circle
			(at 13.999972 0.199898 180)
			(size 0.906272 0.906272)
			(drill 0.499872)
			(layers "*.Cu" "*.Mask")
			(remove_unused_layers no)
			(net "GND")
			(clearance 0.0508)
			(thermal_gap 0.0508)
		)
		(pad "B1" thru_hole circle
			(at 0 1.199896 180)
			(size 0.906272 0.906272)
			(drill 0.499872)
			(layers "*.Cu" "*.Mask")
			(remove_unused_layers no)
			(net "GND")
			(clearance 0.0508)
			(thermal_gap 0.0508)
		)
		(pad "B3" thru_hole circle
			(at 3.999992 1.199896 180)
			(size 0.906272 0.906272)
			(drill 0.499872)
			(layers "*.Cu" "*.Mask")
			(remove_unused_layers no)
			(net "GND")
			(clearance 0.0508)
			(thermal_gap 0.0508)
		)
		(pad "B5" thru_hole circle
			(at 7.999984 1.199896 180)
			(size 0.906272 0.906272)
			(drill 0.499872)
			(layers "*.Cu" "*.Mask")
			(remove_unused_layers no)
			(net "GND")
			(clearance 0.0508)
			(thermal_gap 0.0508)
		)
		(pad "B7" thru_hole circle
			(at 11.999976 1.199896 180)
			(size 0.906272 0.906272)
			(drill 0.499872)
			(layers "*.Cu" "*.Mask")
			(remove_unused_layers no)
			(net "GND")
			(clearance 0.0508)
			(thermal_gap 0.0508)
		)
		(pad "D2" thru_hole circle
			(at 1.999996 3.800094 180)
			(size 0.906272 0.906272)
			(drill 0.499872)
			(layers "*.Cu" "*.Mask")
			(remove_unused_layers no)
			(net "GND")
			(clearance 0.0508)
			(thermal_gap 0.0508)
		)
		(pad "D4" thru_hole circle
			(at 5.999988 3.800094 180)
			(size 0.906272 0.906272)
			(drill 0.499872)
			(layers "*.Cu" "*.Mask")
			(remove_unused_layers no)
			(net "GND")
			(clearance 0.0508)
			(thermal_gap 0.0508)
		)
		(pad "D6" thru_hole circle
			(at 9.99998 3.800094 180)
			(size 0.906272 0.906272)
			(drill 0.499872)
			(layers "*.Cu" "*.Mask")
			(remove_unused_layers no)
			(net "GND")
			(clearance 0.0508)
			(thermal_gap 0.0508)
		)
		(pad "D8" thru_hole circle
			(at 13.999972 3.800094 180)
			(size 0.906272 0.906272)
			(drill 0.499872)
			(layers "*.Cu" "*.Mask")
			(remove_unused_layers no)
			(net "GND")
			(clearance 0.0508)
			(thermal_gap 0.0508)
		)
		(pad "E1" thru_hole circle
			(at 0 4.800092 180)
			(size 0.906272 0.906272)
			(drill 0.499872)
			(layers "*.Cu" "*.Mask")
			(remove_unused_layers no)
			(net "GND")
			(clearance 0.0508)
			(thermal_gap 0.0508)
		)
		(pad "E3" thru_hole circle
			(at 3.999992 4.800092 180)
			(size 0.906272 0.906272)
			(drill 0.499872)
			(layers "*.Cu" "*.Mask")
			(remove_unused_layers no)
			(net "GND")
			(clearance 0.0508)
			(thermal_gap 0.0508)
		)
		(pad "E5" thru_hole circle
			(at 7.999984 4.800092 180)
			(size 0.906272 0.906272)
			(drill 0.499872)
			(layers "*.Cu" "*.Mask")
			(remove_unused_layers no)
			(net "GND")
			(clearance 0.0508)
			(thermal_gap 0.0508)
		)
		(pad "E7" thru_hole circle
			(at 11.999976 4.800092 180)
			(size 0.906272 0.906272)
			(drill 0.499872)
			(layers "*.Cu" "*.Mask")
			(remove_unused_layers no)
			(net "GND")
			(clearance 0.0508)
			(thermal_gap 0.0508)
		)
		(pad "G2" thru_hole circle
			(at 1.999996 7.400036 180)
			(size 0.906272 0.906272)
			(drill 0.499872)
			(layers "*.Cu" "*.Mask")
			(remove_unused_layers no)
			(net "GND")
			(clearance 0.0508)
			(thermal_gap 0.0508)
		)
		(pad "G4" thru_hole circle
			(at 5.999988 7.400036 180)
			(size 0.906272 0.906272)
			(drill 0.499872)
			(layers "*.Cu" "*.Mask")
			(remove_unused_layers no)
			(net "GND")
			(clearance 0.0508)
			(thermal_gap 0.0508)
		)
		(pad "G6" thru_hole circle
			(at 9.99998 7.400036 180)
			(size 0.906272 0.906272)
			(drill 0.499872)
			(layers "*.Cu" "*.Mask")
			(remove_unused_layers no)
			(net "GND")
			(clearance 0.0508)
			(thermal_gap 0.0508)
		)
		(pad "G8" thru_hole circle
			(at 13.999972 7.400036 180)
			(size 0.906272 0.906272)
			(drill 0.499872)
			(layers "*.Cu" "*.Mask")
			(remove_unused_layers no)
			(net "GND")
			(clearance 0.0508)
			(thermal_gap 0.0508)
		)
		(pad "H1" thru_hole circle
			(at 0 8.400034 180)
			(size 0.906272 0.906272)
			(drill 0.499872)
			(layers "*.Cu" "*.Mask")
			(remove_unused_layers no)
			(net "GND")
			(clearance 0.0508)
			(thermal_gap 0.0508)
		)
		(pad "H3" thru_hole circle
			(at 3.999992 8.400034 180)
			(size 0.906272 0.906272)
			(drill 0.499872)
			(layers "*.Cu" "*.Mask")
			(remove_unused_layers no)
			(net "GND")
			(clearance 0.0508)
			(thermal_gap 0.0508)
		)
		(pad "H5" thru_hole circle
			(at 7.999984 8.400034 180)
			(size 0.906272 0.906272)
			(drill 0.499872)
			(layers "*.Cu" "*.Mask")
			(remove_unused_layers no)
			(net "GND")
			(clearance 0.0508)
			(thermal_gap 0.0508)
		)
		(pad "H7" thru_hole circle
			(at 11.999976 8.400034 180)
			(size 0.906272 0.906272)
			(drill 0.499872)
			(layers "*.Cu" "*.Mask")
			(remove_unused_layers no)
			(net "GND")
			(clearance 0.0508)
			(thermal_gap 0.0508)
		)
		(pad "J2" thru_hole circle
			(at 1.999996 10.999978 180)
			(size 0.906272 0.906272)
			(drill 0.499872)
			(layers "*.Cu" "*.Mask")
			(remove_unused_layers no)
			(net "GND")
			(clearance 0.0508)
			(thermal_gap 0.0508)
		)
		(pad "J4" thru_hole circle
			(at 5.999988 10.999978 180)
			(size 0.906272 0.906272)
			(drill 0.499872)
			(layers "*.Cu" "*.Mask")
			(remove_unused_layers no)
			(net "GND")
			(clearance 0.0508)
			(thermal_gap 0.0508)
		)
		(pad "J6" thru_hole circle
			(at 9.99998 10.999978 180)
			(size 0.906272 0.906272)
			(drill 0.499872)
			(layers "*.Cu" "*.Mask")
			(remove_unused_layers no)
			(net "GND")
			(clearance 0.0508)
			(thermal_gap 0.0508)
		)
		(pad "J8" thru_hole circle
			(at 13.999972 10.999978 180)
			(size 0.906272 0.906272)
			(drill 0.499872)
			(layers "*.Cu" "*.Mask")
			(remove_unused_layers no)
			(net "GND")
			(clearance 0.0508)
			(thermal_gap 0.0508)
		)
		(pad "K1" thru_hole circle
			(at 0 11.999976 180)
			(size 0.906272 0.906272)
			(drill 0.499872)
			(layers "*.Cu" "*.Mask")
			(remove_unused_layers no)
			(net "GND")
			(clearance 0.0508)
			(thermal_gap 0.0508)
		)
		(pad "K3" thru_hole circle
			(at 3.999992 11.999976 180)
			(size 0.906272 0.906272)
			(drill 0.499872)
			(layers "*.Cu" "*.Mask")
			(remove_unused_layers no)
			(net "GND")
			(clearance 0.0508)
			(thermal_gap 0.0508)
		)
		(pad "K5" thru_hole circle
			(at 7.999984 11.999976 180)
			(size 0.906272 0.906272)
			(drill 0.499872)
			(layers "*.Cu" "*.Mask")
			(remove_unused_layers no)
			(net "GND")
			(clearance 0.0508)
			(thermal_gap 0.0508)
		)
		(pad "K7" thru_hole circle
			(at 11.999976 11.999976 180)
			(size 0.906272 0.906272)
			(drill 0.499872)
			(layers "*.Cu" "*.Mask")
			(remove_unused_layers no)
			(net "GND")
			(clearance 0.0508)
			(thermal_gap 0.0508)
		)
		(pad "M2" thru_hole circle
			(at 1.999996 14.59992 180)
			(size 0.906272 0.906272)
			(drill 0.499872)
			(layers "*.Cu" "*.Mask")
			(remove_unused_layers no)
			(net "GND")
			(clearance 0.0508)
			(thermal_gap 0.0508)
		)
		(pad "M4" thru_hole circle
			(at 5.999988 14.59992 180)
			(size 0.906272 0.906272)
			(drill 0.499872)
			(layers "*.Cu" "*.Mask")
			(remove_unused_layers no)
			(net "GND")
			(clearance 0.0508)
			(thermal_gap 0.0508)
		)
		(pad "M6" thru_hole circle
			(at 9.99998 14.59992 180)
			(size 0.906272 0.906272)
			(drill 0.499872)
			(layers "*.Cu" "*.Mask")
			(remove_unused_layers no)
			(net "GND")
			(clearance 0.0508)
			(thermal_gap 0.0508)
		)
		(pad "M8" thru_hole circle
			(at 13.999972 14.59992 180)
			(size 0.906272 0.906272)
			(drill 0.499872)
			(layers "*.Cu" "*.Mask")
			(remove_unused_layers no)
			(net "GND")
			(clearance 0.0508)
			(thermal_gap 0.0508)
		)
		(pad "N1" thru_hole circle
			(at 0 15.599918 180)
			(size 0.906272 0.906272)
			(drill 0.499872)
			(layers "*.Cu" "*.Mask")
			(remove_unused_layers no)
			(net "GND")
			(clearance 0.0508)
			(thermal_gap 0.0508)
		)
		(pad "N2" thru_hole circle
			(at 1.999996 15.80007 180)
			(size 0.766318 0.766318)
			(drill 0.359918)
			(layers "*.Cu" "*.Mask")
			(remove_unused_layers no)
			(net "FM_SWB_PWR_EN_R_BUF")
			(clearance 0.0508)
			(thermal_gap 0.0508)
		)
		(pad "N3" thru_hole circle
			(at 3.999992 15.599918 180)
			(size 0.906272 0.906272)
			(drill 0.499872)
			(layers "*.Cu" "*.Mask")
			(remove_unused_layers no)
			(net "GND")
			(clearance 0.0508)
			(thermal_gap 0.0508)
		)
		(pad "N4" thru_hole circle
			(at 5.999988 15.80007 180)
			(size 0.766318 0.766318)
			(drill 0.359918)
			(layers "*.Cu" "*.Mask")
			(remove_unused_layers no)
			(net "FM_SWB_BIC_READY_N")
			(clearance 0.0508)
			(thermal_gap 0.0508)
		)
		(pad "N5" thru_hole circle
			(at 7.999984 15.599918 180)
			(size 0.906272 0.906272)
			(drill 0.499872)
			(layers "*.Cu" "*.Mask")
			(remove_unused_layers no)
			(net "GND")
			(clearance 0.0508)
			(thermal_gap 0.0508)
		)
		(pad "N6" thru_hole circle
			(at 9.99998 15.80007 180)
			(size 0.766318 0.766318)
			(drill 0.359918)
			(layers "*.Cu" "*.Mask")
			(remove_unused_layers no)
			(net "RST_SWB_BIC_BUF_N")
			(clearance 0.0508)
			(thermal_gap 0.0508)
		)
		(pad "N7" thru_hole circle
			(at 11.999976 15.599918 180)
			(size 0.906272 0.906272)
			(drill 0.499872)
			(layers "*.Cu" "*.Mask")
			(remove_unused_layers no)
			(net "GND")
			(clearance 0.0508)
			(thermal_gap 0.0508)
		)
		(pad "N8" thru_hole circle
			(at 13.999972 15.80007 180)
			(size 0.766318 0.766318)
			(drill 0.359918)
			(layers "*.Cu" "*.Mask")
			(remove_unused_layers no)
			(net "RST_BMC_FROM_SWB_N")
			(clearance 0.0508)
			(thermal_gap 0.0508)
		)
	)
)
